# S9S_MB_2U (Grand Teton) — schematic netlist excerpt (pin names and nets, part order shuffled) for the footprints in the layout excerpt that follows; sources: Cadence DE-HDL packaged netlist, KiCad conversion of 03242023_DA0F0TMBIJ0_F0T_Motherboard_J_brd_V01_OCP.brd

PC1355  Q_CAP  0.1UF 25V 10% X7R  pkg 0402  page 267 : A = GND ; B = PVCCIN_CPU0_VREF
R4655  Q_RES  1K 1% EMPTY  pkg 0402LF  page 167 : A = P3V3_AUX ; B = FM_P2E_BUF2_RXDET

(kicad_pcb
	(version 20260206)
	(generator "pcbnew")
	(generator_version "10.0")
	(general
		(thickness 1.6)
		(legacy_teardrops no)
	)
	(paper "A4")
	(title_block
		(title "03242023_DA0F0TMBIJ0_F0T_Motherboard_J_brd_V01_OCP.brd")
		(comment 1 "Grand Teton / footprints 237-238 of 6105")
	)
	(layers
		(0 "F.Cu" signal "TOP")
		(4 "In1.Cu" signal "GND")
		(6 "In2.Cu" signal "IN1")
		(8 "In3.Cu" signal "GND1")
		(10 "In4.Cu" signal "IN2")
		(12 "In5.Cu" signal "GND2")
		(14 "In6.Cu" signal "IN3")
		(16 "In7.Cu" signal "GND3")
		(18 "In8.Cu" signal "VCC")
		(20 "In9.Cu" signal "VCC1")
		(22 "In10.Cu" signal "GND4")
		(24 "In11.Cu" signal "IN4")
		(26 "In12.Cu" signal "GND5")
		(28 "In13.Cu" signal "IN5")
		(30 "In14.Cu" signal "GND6")
		(32 "In15.Cu" signal "IN6")
		(34 "In16.Cu" signal "GND7")
		(2 "B.Cu" signal "BOTTOM")
		(9 "F.Adhes" user "F.Adhesive")
		(11 "B.Adhes" user "B.Adhesive")
		(13 "F.Paste" user "Package Geometry/Pastemask Top")
		(15 "B.Paste" user "Package Geometry/Pastemask Bottom")
		(5 "F.SilkS" user "Ref Des/Silkscreen Top")
		(7 "B.SilkS" user "Ref Des/Silkscreen Bottom")
		(1 "F.Mask" user "Board Geometry/Soldermask Top")
		(3 "B.Mask" user "Board Geometry/Soldermask Bottom")
		(17 "Dwgs.User" user "User.Drawings")
		(19 "Cmts.User" user "User.Comments")
		(21 "Eco1.User" user "User.Eco1")
		(23 "Eco2.User" user "User.Eco2")
		(25 "Edge.Cuts" user "Board Geometry/Outline")
		(27 "Margin" user)
		(31 "F.CrtYd" user "Package Geometry/Place Bound Top")
		(29 "B.CrtYd" user "Package Geometry/Place Bound Bottom")
		(35 "F.Fab" user "Ref Des/Assembly Top")
		(33 "B.Fab" user "Ref Des/Assembly Bottom")
	)
	(footprint ""
		(layer "F.Cu")
		(at 29.904182 -390.084818)
		(property "Reference" "R4655"
			(at 0 0 0)
			(layer "F.SilkS")
			(hide yes)
			(effects
				(font
					(size 1.27 1.27)
				)
			)
		)
		(property "Value" ""
			(at 0 0 0)
			(layer "F.Fab")
			(effects
				(font
					(size 1.27 1.27)
				)
			)
		)
		(duplicate_pad_numbers_are_jumpers no)
		(fp_line
			(start -0.7874 -0.4064)
			(end 0.7874 -0.4064)
			(stroke
				(width 0.1524)
				(type default)
			)
			(layer "F.SilkS")
		)
		(fp_line
			(start -0.7874 0.4064)
			(end -0.7874 -0.4064)
			(stroke
				(width 0.1524)
				(type default)
			)
			(layer "F.SilkS")
		)
		(fp_line
			(start 0.7874 -0.4064)
			(end 0.7874 0.4064)
			(stroke
				(width 0.1524)
				(type default)
			)
			(layer "F.SilkS")
		)
		(fp_line
			(start 0.7874 0.4064)
			(end -0.7874 0.4064)
			(stroke
				(width 0.1524)
				(type default)
			)
			(layer "F.SilkS")
		)
		(fp_line
			(start -0.67945 -0.305054)
			(end -0.12065 -0.305054)
			(stroke
				(width 0.1)
				(type default)
			)
			(layer "F.Fab")
		)
		(fp_line
			(start -0.67945 0.3048)
			(end -0.67945 -0.305054)
			(stroke
				(width 0.1)
				(type default)
			)
			(layer "F.Fab")
		)
		(fp_line
			(start -0.12065 -0.305054)
			(end -0.12065 -0.2794)
			(stroke
				(width 0.1)
				(type default)
			)
			(layer "F.Fab")
		)
		(fp_line
			(start -0.12065 -0.2794)
			(end 0.12065 -0.2794)
			(stroke
				(width 0.1)
				(type default)
			)
			(layer "F.Fab")
		)
		(fp_line
			(start -0.12065 0.2794)
			(end -0.12065 0.3048)
			(stroke
				(width 0.1)
				(type default)
			)
			(layer "F.Fab")
		)
		(fp_line
			(start -0.12065 0.3048)
			(end -0.67945 0.3048)
			(stroke
				(width 0.1)
				(type default)
			)
			(layer "F.Fab")
		)
		(fp_line
			(start 0.120396 0.2794)
			(end -0.12065 0.2794)
			(stroke
				(width 0.1)
				(type default)
			)
			(layer "F.Fab")
		)
		(fp_line
			(start 0.120396 0.3048)
			(end 0.120396 0.2794)
			(stroke
				(width 0.1)
				(type default)
			)
			(layer "F.Fab")
		)
		(fp_line
			(start 0.12065 -0.3048)
			(end 0.67945 -0.3048)
			(stroke
				(width 0.1)
				(type default)
			)
			(layer "F.Fab")
		)
		(fp_line
			(start 0.12065 -0.2794)
			(end 0.12065 -0.3048)
			(stroke
				(width 0.1)
				(type default)
			)
			(layer "F.Fab")
		)
		(fp_line
			(start 0.67945 -0.3048)
			(end 0.67945 0.3048)
			(stroke
				(width 0.1)
				(type default)
			)
			(layer "F.Fab")
		)
		(fp_line
			(start 0.67945 0.3048)
			(end 0.120396 0.3048)
			(stroke
				(width 0.1)
				(type default)
			)
			(layer "F.Fab")
		)
		(pad "1" smd circle
			(at -0.40005 0)
			(size 0 0)
			(layers "F.Cu" "F.Mask" "F.Paste")
			(net "P3V3_AUX")
		)
		(pad "2" smd circle
			(at 0.40005 0)
			(size 0 0)
			(layers "F.Cu" "F.Mask" "F.Paste")
			(net "FM_P2E_BUF2_RXDET")
		)
	)
	(footprint ""
		(layer "F.Cu")
		(at 350.294956 -338.290662 -90)
		(property "Reference" "PC1355"
			(at 0 0 270)
			(layer "F.SilkS")
			(hide yes)
			(effects
				(font
					(size 1.27 1.27)
				)
			)
		)
		(property "Value" ""
			(at 0 0 270)
			(layer "F.Fab")
			(effects
				(font
					(size 1.27 1.27)
				)
			)
		)
		(duplicate_pad_numbers_are_jumpers no)
		(fp_line
			(start -0.7874 0.4064)
			(end -0.7874 -0.4064)
			(stroke
				(width 0.1524)
				(type default)
			)
			(layer "F.SilkS")
		)
		(fp_line
			(start 0.7874 0.4064)
			(end -0.7874 0.4064)
			(stroke
				(width 0.1524)
				(type default)
			)
			(layer "F.SilkS")
		)
		(fp_line
			(start -0.7874 -0.4064)
			(end 0.7874 -0.4064)
			(stroke
				(width 0.1524)
				(type default)
			)
			(layer "F.SilkS")
		)
		(fp_line
			(start 0.7874 -0.4064)
			(end 0.7874 0.4064)
			(stroke
				(width 0.1524)
				(type default)
			)
			(layer "F.SilkS")
		)
		(fp_line
			(start -0.67945 0.3048)
			(end -0.67945 -0.305054)
			(stroke
				(width 0.1)
				(type default)
			)
			(layer "F.Fab")
		)
		(fp_line
			(start -0.12065 0.3048)
			(end -0.67945 0.3048)
			(stroke
				(width 0.1)
				(type default)
			)
			(layer "F.Fab")
		)
		(fp_line
			(start 0.120396 0.3048)
			(end 0.120396 0.2794)
			(stroke
				(width 0.1)
				(type default)
			)
			(layer "F.Fab")
		)
		(fp_line
			(start 0.67945 0.3048)
			(end 0.120396 0.3048)
			(stroke
				(width 0.1)
				(type default)
			)
			(layer "F.Fab")
		)
		(fp_line
			(start -0.12065 0.2794)
			(end -0.12065 0.3048)
			(stroke
				(width 0.1)
				(type default)
			)
			(layer "F.Fab")
		)
		(fp_line
			(start 0.120396 0.2794)
			(end -0.12065 0.2794)
			(stroke
				(width 0.1)
				(type default)
			)
			(layer "F.Fab")
		)
		(fp_line
			(start -0.12065 -0.2794)
			(end 0.12065 -0.2794)
			(stroke
				(width 0.1)
				(type default)
			)
			(layer "F.Fab")
		)
		(fp_line
			(start 0.12065 -0.2794)
			(end 0.12065 -0.3048)
			(stroke
				(width 0.1)
				(type default)
			)
			(layer "F.Fab")
		)
		(fp_line
			(start 0.12065 -0.3048)
			(end 0.67945 -0.3048)
			(stroke
				(width 0.1)
				(type default)
			)
			(layer "F.Fab")
		)
		(fp_line
			(start 0.67945 -0.3048)
			(end 0.67945 0.3048)
			(stroke
				(width 0.1)
				(type default)
			)
			(layer "F.Fab")
		)
		(fp_line
			(start -0.67945 -0.305054)
			(end -0.12065 -0.305054)
			(stroke
				(width 0.1)
				(type default)
			)
			(layer "F.Fab")
		)
		(fp_line
			(start -0.12065 -0.305054)
			(end -0.12065 -0.2794)
			(stroke
				(width 0.1)
				(type default)
			)
			(layer "F.Fab")
		)
		(pad "1" smd circle
			(at -0.40005 0 270)
			(size 0 0)
			(layers "F.Cu" "F.Mask" "F.Paste")
			(net "GND")
		)
		(pad "2" smd circle
			(at 0.40005 0 270)
			(size 0 0)
			(layers "F.Cu" "F.Mask" "F.Paste")
			(net "PVCCIN_CPU0_VREF")
		)
	)
)
